(kicad_pcb
	(version 20260206)
	(generator "pcbnew")
	(generator_version "10.0")
	(general
		(thickness 1.6)
		(legacy_teardrops no)
	)
	(paper "A4")
	(title_block
		(title "peb — Lightning_PEB_BRD.brd")
		(comment 1 "Lightning (Wiwynn / Facebook NVMe JBOF) / footprints 1557-1564 of 2563")
	)
	(layers
		(0 "F.Cu" signal "TOP")
		(4 "In1.Cu" signal "L2GND")
		(6 "In2.Cu" signal "L3")
		(8 "In3.Cu" signal "L4VCC")
		(10 "In4.Cu" signal "L5VCC")
		(12 "In5.Cu" signal "L6")
		(14 "In6.Cu" signal "L7GND")
		(2 "B.Cu" signal "BOTTOM")
		(9 "F.Adhes" user "F.Adhesive")
		(11 "B.Adhes" user "B.Adhesive")
		(13 "F.Paste" user "Package Geometry/Pastemask Top")
		(15 "B.Paste" user "Package Geometry/Pastemask Bottom")
		(5 "F.SilkS" user "Ref Des/Silkscreen Top")
		(7 "B.SilkS" user "Ref Des/Silkscreen Bottom")
		(1 "F.Mask" user "Board Geometry/Soldermask Top")
		(3 "B.Mask" user "Board Geometry/Soldermask Bottom")
		(17 "Dwgs.User" user "User.Drawings")
		(19 "Cmts.User" user "User.Comments")
		(21 "Eco1.User" user "User.Eco1")
		(23 "Eco2.User" user "User.Eco2")
		(25 "Edge.Cuts" user "Board Geometry/Outline")
		(27 "Margin" user)
		(31 "F.CrtYd" user "Package Geometry/Place Bound Top")
		(29 "B.CrtYd" user "Package Geometry/Place Bound Bottom")
		(35 "F.Fab" user "Ref Des/Assembly Top")
		(33 "B.Fab" user "Ref Des/Assembly Bottom")
	)
	(footprint ""
		(layer "F.Cu")
		(at 78.081124 -195.681092 180)
		(property "Reference" "R7963"
			(at 0 0 180)
			(layer "F.SilkS")
			(hide yes)
			(effects
				(font
					(size 1.27 1.27)
				)
			)
		)
		(property "Value" "0R2J-2-GP"
			(at 0.064008 -3.993896 180)
			(unlocked yes)
			(layer "F.Fab")
			(hide yes)
			(effects
				(font
					(size 1.016 1.016)
					(thickness 0.1524)
				)
			)
		)
		(property "Device Type" "R402H16"
			(at 0.064008 -5.517896 180)
			(unlocked yes)
			(layer "F.Fab")
			(hide yes)
			(effects
				(font
					(size 1.016 1.016)
					(thickness 0.1524)
				)
			)
		)
		(duplicate_pad_numbers_are_jumpers no)
		(fp_line
			(start 0.508 -0.9398)
			(end -0.508 -0.9398)
			(stroke
				(width 0.1524)
				(type default)
			)
			(layer "F.SilkS")
		)
		(fp_line
			(start -0.508 -0.9398)
			(end -0.508 0.9398)
			(stroke
				(width 0.1524)
				(type default)
			)
			(layer "F.SilkS")
		)
		(fp_rect
			(start -0.508 0.9398)
			(end 0.508 -0.9398)
			(stroke
				(width 0)
				(type default)
			)
			(fill no)
			(layer "F.CrtYd")
		)
		(fp_rect
			(start -0.508 0.9398)
			(end 0.508 -0.9398)
			(stroke
				(width 0)
				(type default)
			)
			(fill no)
			(layer "F.Fab")
		)
		(pad "1" smd custom
			(at 0 -0.4445 180)
			(size 0.1397 0.1397)
			(layers "F.Cu" "F.Mask" "F.Paste")
			(net "SSD_PWREN10")
			(options
				(clearance outline)
				(anchor circle)
			)
			(primitives
				(gr_poly
					(pts
						(arc
							(start -0.1778 -0.2794)
							(mid -0.249642 -0.249642)
							(end -0.2794 -0.1778)
						)
						(arc
							(start -0.2794 0.1778)
							(mid -0.249642 0.249642)
							(end -0.1778 0.2794)
						)
						(arc
							(start 0.1778 0.2794)
							(mid 0.249642 0.249642)
							(end 0.2794 0.1778)
						)
						(arc
							(start 0.2794 -0.1778)
							(mid 0.249642 -0.249642)
							(end 0.1778 -0.2794)
						)
					)
					(width 0)
					(fill yes)
				)
			)
		)
		(pad "2" smd custom
			(at 0 0.4445 180)
			(size 0.1397 0.1397)
			(layers "F.Cu" "F.Mask" "F.Paste")
			(net "SSD_PWREN10_R")
			(options
				(clearance outline)
				(anchor circle)
			)
			(primitives
				(gr_poly
					(pts
						(arc
							(start -0.1778 -0.2794)
							(mid -0.249642 -0.249642)
							(end -0.2794 -0.1778)
						)
						(arc
							(start -0.2794 0.1778)
							(mid -0.249642 0.249642)
							(end -0.1778 0.2794)
						)
						(arc
							(start 0.1778 0.2794)
							(mid 0.249642 0.249642)
							(end 0.2794 0.1778)
						)
						(arc
							(start 0.2794 -0.1778)
							(mid 0.249642 -0.249642)
							(end 0.1778 -0.2794)
						)
					)
					(width 0)
					(fill yes)
				)
			)
		)
	)
	(footprint ""
		(layer "F.Cu")
		(at 120.1928 -93.4212 -90)
		(property "Reference" "C247"
			(at 0 0 270)
			(layer "F.SilkS")
			(hide yes)
			(effects
				(font
					(size 1.27 1.27)
				)
			)
		)
		(property "Value" "SC220P50V3JN-GP"
			(at 0 -2.8194 270)
			(unlocked yes)
			(layer "F.Fab")
			(hide yes)
			(effects
				(font
					(size 1.016 1.016)
					(thickness 0.1524)
				)
			)
		)
		(property "Device Type" "C603H36"
			(at 0 -4.3434 270)
			(unlocked yes)
			(layer "F.Fab")
			(hide yes)
			(effects
				(font
					(size 1.016 1.016)
					(thickness 0.1524)
				)
			)
		)
		(duplicate_pad_numbers_are_jumpers no)
		(fp_line
			(start 0.508 0)
			(end -0.508 0)
			(stroke
				(width 0.2032)
				(type default)
			)
			(layer "F.SilkS")
		)
		(fp_rect
			(start -0.5842 1.3335)
			(end 0.5842 -1.3335)
			(stroke
				(width 0)
				(type default)
			)
			(fill no)
			(layer "F.CrtYd")
		)
		(fp_rect
			(start -0.5842 1.3335)
			(end 0.5842 -1.3335)
			(stroke
				(width 0)
				(type default)
			)
			(fill no)
			(layer "F.Fab")
		)
		(pad "1" smd custom
			(at 0 -0.762 270)
			(size 0.2159 0.2159)
			(layers "F.Cu" "F.Mask" "F.Paste")
			(net "BMC_I2C10_8536_SDA_R")
			(options
				(clearance outline)
				(anchor circle)
			)
			(primitives
				(gr_poly
					(pts
						(arc
							(start -0.3302 -0.4318)
							(mid -0.402042 -0.402042)
							(end -0.4318 -0.3302)
						)
						(arc
							(start -0.4318 0.3302)
							(mid -0.402042 0.402042)
							(end -0.3302 0.4318)
						)
						(arc
							(start 0.3302 0.4318)
							(mid 0.402042 0.402042)
							(end 0.4318 0.3302)
						)
						(arc
							(start 0.4318 -0.3302)
							(mid 0.402042 -0.402042)
							(end 0.3302 -0.4318)
						)
					)
					(width 0)
					(fill yes)
				)
			)
		)
		(pad "2" smd custom
			(at 0 0.762 270)
			(size 0.2159 0.2159)
			(layers "F.Cu" "F.Mask" "F.Paste")
			(net "GND")
			(options
				(clearance outline)
				(anchor circle)
			)
			(primitives
				(gr_poly
					(pts
						(arc
							(start -0.3302 -0.4318)
							(mid -0.402042 -0.402042)
							(end -0.4318 -0.3302)
						)
						(arc
							(start -0.4318 0.3302)
							(mid -0.402042 0.402042)
							(end -0.3302 0.4318)
						)
						(arc
							(start 0.3302 0.4318)
							(mid 0.402042 0.402042)
							(end 0.4318 0.3302)
						)
						(arc
							(start 0.4318 -0.3302)
							(mid 0.402042 -0.402042)
							(end 0.3302 -0.4318)
						)
					)
					(width 0)
					(fill yes)
				)
			)
		)
	)
	(footprint ""
		(layer "F.Cu")
		(at 137.5283 -33.54324)
		(property "Reference" "C387"
			(at 0 0 0)
			(layer "F.SilkS")
			(hide yes)
			(effects
				(font
					(size 1.27 1.27)
				)
			)
		)
		(property "Value" "SCD22U10V2KX-1GP"
			(at 1.1811 -2.7051 0)
			(unlocked yes)
			(layer "F.Fab")
			(hide yes)
			(effects
				(font
					(size 1.016 1.016)
					(thickness 0.1524)
				)
			)
		)
		(property "Device Type" "C402H22"
			(at 1.1811 -4.2291 0)
			(unlocked yes)
			(layer "F.Fab")
			(hide yes)
			(effects
				(font
					(size 1.016 1.016)
					(thickness 0.1524)
				)
			)
		)
		(duplicate_pad_numbers_are_jumpers no)
		(fp_rect
			(start -0.4318 0.9525)
			(end 0.4318 -0.9525)
			(stroke
				(width 0)
				(type default)
			)
			(fill no)
			(layer "F.CrtYd")
		)
		(fp_rect
			(start -0.4318 0.9525)
			(end 0.4318 -0.9525)
			(stroke
				(width 0)
				(type default)
			)
			(fill no)
			(layer "F.Fab")
		)
		(pad "1" smd custom
			(at 0 -0.4445)
			(size 0.1524 0.1524)
			(layers "F.Cu" "F.Mask" "F.Paste")
			(net "PCIE_TX_CAP_P83")
			(options
				(clearance outline)
				(anchor circle)
			)
			(primitives
				(gr_poly
					(pts
						(arc
							(start 0.3048 -0.2032)
							(mid 0.275042 -0.275042)
							(end 0.2032 -0.3048)
						)
						(arc
							(start -0.2032 -0.3048)
							(mid -0.275042 -0.275042)
							(end -0.3048 -0.2032)
						)
						(arc
							(start -0.3048 0.2032)
							(mid -0.275042 0.275042)
							(end -0.2032 0.3048)
						)
						(arc
							(start 0.2032 0.3048)
							(mid 0.275042 0.275042)
							(end 0.3048 0.2032)
						)
					)
					(width 0)
					(fill yes)
				)
			)
		)
		(pad "2" smd custom
			(at 0 0.4445)
			(size 0.1524 0.1524)
			(layers "F.Cu" "F.Mask" "F.Paste")
			(net "PCIE_TX_P83")
			(options
				(clearance outline)
				(anchor circle)
			)
			(primitives
				(gr_poly
					(pts
						(arc
							(start 0.3048 -0.2032)
							(mid 0.275042 -0.275042)
							(end 0.2032 -0.3048)
						)
						(arc
							(start -0.2032 -0.3048)
							(mid -0.275042 -0.275042)
							(end -0.3048 -0.2032)
						)
						(arc
							(start -0.3048 0.2032)
							(mid -0.275042 0.275042)
							(end -0.2032 0.3048)
						)
						(arc
							(start 0.2032 0.3048)
							(mid 0.275042 0.275042)
							(end 0.3048 0.2032)
						)
					)
					(width 0)
					(fill yes)
				)
			)
		)
	)
	(footprint ""
		(layer "F.Cu")
		(at 273.699986 -0.127 -90)
		(property "Reference" "R2906"
			(at 0 0 270)
			(layer "F.SilkS")
			(hide yes)
			(effects
				(font
					(size 1.27 1.27)
				)
			)
		)
		(property "Value" "0R2J-2-GP"
			(at 0.064008 -3.993896 270)
			(unlocked yes)
			(layer "F.Fab")
			(hide yes)
			(effects
				(font
					(size 1.016 1.016)
					(thickness 0.1524)
				)
			)
		)
		(property "Device Type" "R402H16"
			(at 0.064008 -5.517896 270)
			(unlocked yes)
			(layer "F.Fab")
			(hide yes)
			(effects
				(font
					(size 1.016 1.016)
					(thickness 0.1524)
				)
			)
		)
		(duplicate_pad_numbers_are_jumpers no)
		(fp_line
			(start -0.508 -0.9398)
			(end -0.508 0.9398)
			(stroke
				(width 0.1524)
				(type default)
			)
			(layer "F.SilkS")
		)
		(fp_line
			(start 0.508 -0.9398)
			(end -0.508 -0.9398)
			(stroke
				(width 0.1524)
				(type default)
			)
			(layer "F.SilkS")
		)
		(fp_rect
			(start -0.508 0.9398)
			(end 0.508 -0.9398)
			(stroke
				(width 0)
				(type default)
			)
			(fill no)
			(layer "F.CrtYd")
		)
		(fp_rect
			(start -0.508 0.9398)
			(end 0.508 -0.9398)
			(stroke
				(width 0)
				(type default)
			)
			(fill no)
			(layer "F.Fab")
		)
		(pad "1" smd custom
			(at 0 -0.4445 270)
			(size 0.1397 0.1397)
			(layers "F.Cu" "F.Mask" "F.Paste")
			(net "CBL_PRSNT_N_7")
			(options
				(clearance outline)
				(anchor circle)
			)
			(primitives
				(gr_poly
					(pts
						(arc
							(start -0.1778 -0.2794)
							(mid -0.249642 -0.249642)
							(end -0.2794 -0.1778)
						)
						(arc
							(start -0.2794 0.1778)
							(mid -0.249642 0.249642)
							(end -0.1778 0.2794)
						)
						(arc
							(start 0.1778 0.2794)
							(mid 0.249642 0.249642)
							(end 0.2794 0.1778)
						)
						(arc
							(start 0.2794 -0.1778)
							(mid 0.249642 -0.249642)
							(end 0.1778 -0.2794)
						)
					)
					(width 0)
					(fill yes)
				)
			)
		)
		(pad "2" smd custom
			(at 0 0.4445 270)
			(size 0.1397 0.1397)
			(layers "F.Cu" "F.Mask" "F.Paste")
			(net "8644_CBL_PRSNT_R_7")
			(options
				(clearance outline)
				(anchor circle)
			)
			(primitives
				(gr_poly
					(pts
						(arc
							(start -0.1778 -0.2794)
							(mid -0.249642 -0.249642)
							(end -0.2794 -0.1778)
						)
						(arc
							(start -0.2794 0.1778)
							(mid -0.249642 0.249642)
							(end -0.1778 0.2794)
						)
						(arc
							(start 0.1778 0.2794)
							(mid 0.249642 0.249642)
							(end 0.2794 0.1778)
						)
						(arc
							(start 0.2794 -0.1778)
							(mid 0.249642 -0.249642)
							(end 0.1778 -0.2794)
						)
					)
					(width 0)
					(fill yes)
				)
			)
		)
	)
	(footprint ""
		(layer "F.Cu")
		(at 163.068 -97.5614 90)
		(property "Reference" "TP80"
			(at 0 0 90)
			(layer "F.SilkS")
			(hide yes)
			(effects
				(font
					(size 1.27 1.27)
				)
			)
		)
		(property "Value" "TPAD28-2-GP"
			(at -0.0127 -1.6637 90)
			(unlocked yes)
			(layer "F.Fab")
			(hide yes)
			(effects
				(font
					(size 1.016 1.016)
					(thickness 0.1524)
				)
			)
		)
		(property "Device Type" "TPAD28"
			(at -0.0127 -3.1877 90)
			(unlocked yes)
			(layer "F.Fab")
			(hide yes)
			(effects
				(font
					(size 1.016 1.016)
					(thickness 0.1524)
				)
			)
		)
		(duplicate_pad_numbers_are_jumpers no)
		(fp_poly
			(pts
				(arc
					(start 0 0.3556)
					(mid 0 -0.3556)
					(end 0 0.3556)
				)
			)
			(stroke
				(width 0)
				(type default)
			)
			(fill no)
			(layer "F.CrtYd")
		)
		(fp_poly
			(pts
				(arc
					(start 0 0.6096)
					(mid 0 -0.6096)
					(end 0 0.6096)
				)
			)
			(stroke
				(width 0)
				(type default)
			)
			(fill no)
			(layer "F.Fab")
		)
		(pad "1" smd circle
			(at 0 0 90)
			(size 0.7112 0.7112)
			(layers "F.Cu" "F.Mask" "F.Paste")
			(net "CLKGEN_P3")
		)
	)
	(footprint ""
		(layer "F.Cu")
		(at 150.231602 -54.688232 -90)
		(property "Reference" "R68"
			(at 0 0 270)
			(layer "F.SilkS")
			(hide yes)
			(effects
				(font
					(size 1.27 1.27)
				)
			)
		)
		(property "Value" "20KR2F-L-GP"
			(at 0.064008 -3.993896 270)
			(unlocked yes)
			(layer "F.Fab")
			(hide yes)
			(effects
				(font
					(size 1.016 1.016)
					(thickness 0.1524)
				)
			)
		)
		(property "Device Type" "R402H16"
			(at 0.064008 -5.517896 270)
			(unlocked yes)
			(layer "F.Fab")
			(hide yes)
			(effects
				(font
					(size 1.016 1.016)
					(thickness 0.1524)
				)
			)
		)
		(duplicate_pad_numbers_are_jumpers no)
		(fp_line
			(start -0.508 -0.9398)
			(end -0.508 0.9398)
			(stroke
				(width 0.1524)
				(type default)
			)
			(layer "F.SilkS")
		)
		(fp_line
			(start 0.508 -0.9398)
			(end -0.508 -0.9398)
			(stroke
				(width 0.1524)
				(type default)
			)
			(layer "F.SilkS")
		)
		(fp_rect
			(start -0.508 0.9398)
			(end 0.508 -0.9398)
			(stroke
				(width 0)
				(type default)
			)
			(fill no)
			(layer "F.CrtYd")
		)
		(fp_rect
			(start -0.508 0.9398)
			(end 0.508 -0.9398)
			(stroke
				(width 0)
				(type default)
			)
			(fill no)
			(layer "F.Fab")
		)
		(pad "1" smd custom
			(at 0 -0.4445 270)
			(size 0.1397 0.1397)
			(layers "F.Cu" "F.Mask" "F.Paste")
			(net "DUT_VDDO")
			(options
				(clearance outline)
				(anchor circle)
			)
			(primitives
				(gr_poly
					(pts
						(arc
							(start -0.1778 -0.2794)
							(mid -0.249642 -0.249642)
							(end -0.2794 -0.1778)
						)
						(arc
							(start -0.2794 0.1778)
							(mid -0.249642 0.249642)
							(end -0.1778 0.2794)
						)
						(arc
							(start 0.1778 0.2794)
							(mid 0.249642 0.249642)
							(end 0.2794 0.1778)
						)
						(arc
							(start 0.2794 -0.1778)
							(mid 0.249642 -0.249642)
							(end 0.1778 -0.2794)
						)
					)
					(width 0)
					(fill yes)
				)
			)
		)
		(pad "2" smd custom
			(at 0 0.4445 270)
			(size 0.1397 0.1397)
			(layers "F.Cu" "F.Mask" "F.Paste")
			(net "AVS_ENB1_R")
			(options
				(clearance outline)
				(anchor circle)
			)
			(primitives
				(gr_poly
					(pts
						(arc
							(start -0.1778 -0.2794)
							(mid -0.249642 -0.249642)
							(end -0.2794 -0.1778)
						)
						(arc
							(start -0.2794 0.1778)
							(mid -0.249642 0.249642)
							(end -0.1778 0.2794)
						)
						(arc
							(start 0.1778 0.2794)
							(mid 0.249642 0.249642)
							(end 0.2794 0.1778)
						)
						(arc
							(start 0.2794 -0.1778)
							(mid 0.249642 -0.249642)
							(end 0.1778 -0.2794)
						)
					)
					(width 0)
					(fill yes)
				)
			)
		)
	)
	(footprint ""
		(layer "F.Cu")
		(at 252.627638 -14.190726)
		(property "Reference" "PC224"
			(at 0 0 0)
			(layer "F.SilkS")
			(hide yes)
			(effects
				(font
					(size 1.27 1.27)
				)
			)
		)
		(property "Value" "SC1U16V3KX-5GP"
			(at 0 -2.8194 0)
			(unlocked yes)
			(layer "F.Fab")
			(hide yes)
			(effects
				(font
					(size 1.016 1.016)
					(thickness 0.1524)
				)
			)
		)
		(property "Device Type" "C603H36"
			(at 0 -4.3434 0)
			(unlocked yes)
			(layer "F.Fab")
			(hide yes)
			(effects
				(font
					(size 1.016 1.016)
					(thickness 0.1524)
				)
			)
		)
		(duplicate_pad_numbers_are_jumpers no)
		(fp_line
			(start 0.508 0)
			(end -0.508 0)
			(stroke
				(width 0.2032)
				(type default)
			)
			(layer "F.SilkS")
		)
		(fp_rect
			(start -0.5842 1.3335)
			(end 0.5842 -1.3335)
			(stroke
				(width 0)
				(type default)
			)
			(fill no)
			(layer "F.CrtYd")
		)
		(fp_rect
			(start -0.5842 1.3335)
			(end 0.5842 -1.3335)
			(stroke
				(width 0)
				(type default)
			)
			(fill no)
			(layer "F.Fab")
		)
		(pad "1" smd custom
			(at 0 -0.762)
			(size 0.2159 0.2159)
			(layers "F.Cu" "F.Mask" "F.Paste")
			(net "P3V3_GPIO")
			(options
				(clearance outline)
				(anchor circle)
			)
			(primitives
				(gr_poly
					(pts
						(arc
							(start -0.3302 -0.4318)
							(mid -0.402042 -0.402042)
							(end -0.4318 -0.3302)
						)
						(arc
							(start -0.4318 0.3302)
							(mid -0.402042 0.402042)
							(end -0.3302 0.4318)
						)
						(arc
							(start 0.3302 0.4318)
							(mid 0.402042 0.402042)
							(end 0.4318 0.3302)
						)
						(arc
							(start 0.4318 -0.3302)
							(mid 0.402042 -0.402042)
							(end 0.3302 -0.4318)
						)
					)
					(width 0)
					(fill yes)
				)
			)
		)
		(pad "2" smd custom
			(at 0 0.762)
			(size 0.2159 0.2159)
			(layers "F.Cu" "F.Mask" "F.Paste")
			(net "GND")
			(options
				(clearance outline)
				(anchor circle)
			)
			(primitives
				(gr_poly
					(pts
						(arc
							(start -0.3302 -0.4318)
							(mid -0.402042 -0.402042)
							(end -0.4318 -0.3302)
						)
						(arc
							(start -0.4318 0.3302)
							(mid -0.402042 0.402042)
							(end -0.3302 0.4318)
						)
						(arc
							(start 0.3302 0.4318)
							(mid 0.402042 0.402042)
							(end 0.4318 0.3302)
						)
						(arc
							(start 0.4318 -0.3302)
							(mid 0.402042 -0.402042)
							(end 0.3302 -0.4318)
						)
					)
					(width 0)
					(fill yes)
				)
			)
		)
	)
	(footprint ""
		(layer "F.Cu")
		(at 5.8674 -55.5498 180)
		(property "Reference" "C422"
			(at 0 0 180)
			(layer "F.SilkS")
			(hide yes)
			(effects
				(font
					(size 1.27 1.27)
				)
			)
		)
		(property "Value" "SCD1U16V2KX-3GP"
			(at 1.1811 -2.7051 180)
			(unlocked yes)
			(layer "F.Fab")
			(hide yes)
			(effects
				(font
					(size 1.016 1.016)
					(thickness 0.1524)
				)
			)
		)
		(property "Device Type" "C402H22"
			(at 1.1811 -4.2291 180)
			(unlocked yes)
			(layer "F.Fab")
			(hide yes)
			(effects
				(font
					(size 1.016 1.016)
					(thickness 0.1524)
				)
			)
		)
		(duplicate_pad_numbers_are_jumpers no)
		(fp_rect
			(start -0.4318 0.9525)
			(end 0.4318 -0.9525)
			(stroke
				(width 0)
				(type default)
			)
			(fill no)
			(layer "F.CrtYd")
		)
		(fp_rect
			(start -0.4318 0.9525)
			(end 0.4318 -0.9525)
			(stroke
				(width 0)
				(type default)
			)
			(fill no)
			(layer "F.Fab")
		)
		(pad "1" smd custom
			(at 0 -0.4445 180)
			(size 0.1524 0.1524)
			(layers "F.Cu" "F.Mask" "F.Paste")
			(net "LED_MDI0_ACT")
			(options
				(clearance outline)
				(anchor circle)
			)
			(primitives
				(gr_poly
					(pts
						(arc
							(start 0.3048 -0.2032)
							(mid 0.275042 -0.275042)
							(end 0.2032 -0.3048)
						)
						(arc
							(start -0.2032 -0.3048)
							(mid -0.275042 -0.275042)
							(end -0.3048 -0.2032)
						)
						(arc
							(start -0.3048 0.2032)
							(mid -0.275042 0.275042)
							(end -0.2032 0.3048)
						)
						(arc
							(start 0.2032 0.3048)
							(mid 0.275042 0.275042)
							(end 0.3048 0.2032)
						)
					)
					(width 0)
					(fill yes)
				)
			)
		)
		(pad "2" smd custom
			(at 0 0.4445 180)
			(size 0.1524 0.1524)
			(layers "F.Cu" "F.Mask" "F.Paste")
			(net "GND")
			(options
				(clearance outline)
				(anchor circle)
			)
			(primitives
				(gr_poly
					(pts
						(arc
							(start 0.3048 -0.2032)
							(mid 0.275042 -0.275042)
							(end 0.2032 -0.3048)
						)
						(arc
							(start -0.2032 -0.3048)
							(mid -0.275042 -0.275042)
							(end -0.3048 -0.2032)
						)
						(arc
							(start -0.3048 0.2032)
							(mid -0.275042 0.275042)
							(end -0.2032 0.3048)
						)
						(arc
							(start 0.2032 0.3048)
							(mid 0.275042 0.275042)
							(end 0.3048 0.2032)
						)
					)
					(width 0)
					(fill yes)
				)
			)
		)
	)
)
